(kicad_pcb
	(version 20260206)
	(generator "pcbnew")
	(generator_version "10.0")
	(general
		(thickness 1.6)
		(legacy_teardrops no)
	)
	(paper "A4")
	(title_block
		(title "04192023_DAF0TMB3IC0_F0TG_MB_C_brd_V02_OCP.brd")
		(comment 1 "Grand Teton / footprints 3517-3522 of 8354")
	)
	(layers
		(0 "F.Cu" signal "TOP")
		(4 "In1.Cu" signal "GND")
		(6 "In2.Cu" signal "IN1")
		(8 "In3.Cu" signal "GND1")
		(10 "In4.Cu" signal "IN2")
		(12 "In5.Cu" signal "GND2")
		(14 "In6.Cu" signal "IN3")
		(16 "In7.Cu" signal "GND3")
		(18 "In8.Cu" signal "VCC")
		(20 "In9.Cu" signal "VCC1")
		(22 "In10.Cu" signal "GND4")
		(24 "In11.Cu" signal "IN4")
		(26 "In12.Cu" signal "GND5")
		(28 "In13.Cu" signal "IN5")
		(30 "In14.Cu" signal "GND6")
		(32 "In15.Cu" signal "IN6")
		(34 "In16.Cu" signal "GND7")
		(2 "B.Cu" signal "BOTTOM")
		(9 "F.Adhes" user "F.Adhesive")
		(11 "B.Adhes" user "B.Adhesive")
		(13 "F.Paste" user "Package Geometry/Pastemask Top")
		(15 "B.Paste" user "Package Geometry/Pastemask Bottom")
		(5 "F.SilkS" user "Ref Des/Silkscreen Top")
		(7 "B.SilkS" user "Ref Des/Silkscreen Bottom")
		(1 "F.Mask" user "Board Geometry/Soldermask Top")
		(3 "B.Mask" user "Board Geometry/Soldermask Bottom")
		(17 "Dwgs.User" user "User.Drawings")
		(19 "Cmts.User" user "User.Comments")
		(21 "Eco1.User" user "User.Eco1")
		(23 "Eco2.User" user "User.Eco2")
		(25 "Edge.Cuts" user "Board Geometry/Outline")
		(27 "Margin" user)
		(31 "F.CrtYd" user "Package Geometry/Place Bound Top")
		(29 "B.CrtYd" user "Package Geometry/Place Bound Bottom")
		(35 "F.Fab" user "Ref Des/Assembly Top")
		(33 "B.Fab" user "Ref Des/Assembly Bottom")
	)
	(footprint ""
		(layer "F.Cu")
		(at 197.269608 -109.561376 180)
		(property "Reference" "R280"
			(at 0 0 180)
			(layer "F.SilkS")
			(hide yes)
			(effects
				(font
					(size 1.27 1.27)
				)
			)
		)
		(property "Value" ""
			(at 0 0 180)
			(layer "F.Fab")
			(effects
				(font
					(size 1.27 1.27)
				)
			)
		)
		(duplicate_pad_numbers_are_jumpers no)
		(fp_line
			(start 0.7874 0.4064)
			(end -0.7874 0.4064)
			(stroke
				(width 0.1524)
				(type default)
			)
			(layer "F.SilkS")
		)
		(fp_line
			(start 0.7874 -0.4064)
			(end 0.7874 0.4064)
			(stroke
				(width 0.1524)
				(type default)
			)
			(layer "F.SilkS")
		)
		(fp_line
			(start -0.7874 0.4064)
			(end -0.7874 -0.4064)
			(stroke
				(width 0.1524)
				(type default)
			)
			(layer "F.SilkS")
		)
		(fp_line
			(start -0.7874 -0.4064)
			(end 0.7874 -0.4064)
			(stroke
				(width 0.1524)
				(type default)
			)
			(layer "F.SilkS")
		)
		(fp_line
			(start 0.67945 0.3048)
			(end 0.120396 0.3048)
			(stroke
				(width 0.1)
				(type default)
			)
			(layer "F.Fab")
		)
		(fp_line
			(start 0.67945 -0.3048)
			(end 0.67945 0.3048)
			(stroke
				(width 0.1)
				(type default)
			)
			(layer "F.Fab")
		)
		(fp_line
			(start 0.12065 -0.2794)
			(end 0.12065 -0.3048)
			(stroke
				(width 0.1)
				(type default)
			)
			(layer "F.Fab")
		)
		(fp_line
			(start 0.12065 -0.3048)
			(end 0.67945 -0.3048)
			(stroke
				(width 0.1)
				(type default)
			)
			(layer "F.Fab")
		)
		(fp_line
			(start 0.120396 0.3048)
			(end 0.120396 0.2794)
			(stroke
				(width 0.1)
				(type default)
			)
			(layer "F.Fab")
		)
		(fp_line
			(start 0.120396 0.2794)
			(end -0.12065 0.2794)
			(stroke
				(width 0.1)
				(type default)
			)
			(layer "F.Fab")
		)
		(fp_line
			(start -0.12065 0.3048)
			(end -0.67945 0.3048)
			(stroke
				(width 0.1)
				(type default)
			)
			(layer "F.Fab")
		)
		(fp_line
			(start -0.12065 0.2794)
			(end -0.12065 0.3048)
			(stroke
				(width 0.1)
				(type default)
			)
			(layer "F.Fab")
		)
		(fp_line
			(start -0.12065 -0.2794)
			(end 0.12065 -0.2794)
			(stroke
				(width 0.1)
				(type default)
			)
			(layer "F.Fab")
		)
		(fp_line
			(start -0.12065 -0.305054)
			(end -0.12065 -0.2794)
			(stroke
				(width 0.1)
				(type default)
			)
			(layer "F.Fab")
		)
		(fp_line
			(start -0.67945 0.3048)
			(end -0.67945 -0.305054)
			(stroke
				(width 0.1)
				(type default)
			)
			(layer "F.Fab")
		)
		(fp_line
			(start -0.67945 -0.305054)
			(end -0.12065 -0.305054)
			(stroke
				(width 0.1)
				(type default)
			)
			(layer "F.Fab")
		)
		(pad "1" smd circle
			(at -0.40005 0 180)
			(size 0 0)
			(layers "F.Cu" "F.Mask" "F.Paste")
			(net "PWRGD_PVDD11_S3_P1")
		)
		(pad "2" smd circle
			(at 0.40005 0 180)
			(size 0 0)
			(layers "F.Cu" "F.Mask" "F.Paste")
			(net "FM_PWRGD_PVDD11_S3_P1")
		)
	)
	(footprint ""
		(layer "F.Cu")
		(at 186.055 -129.377948 90)
		(property "Reference" "R250"
			(at 0 0 90)
			(layer "F.SilkS")
			(hide yes)
			(effects
				(font
					(size 1.27 1.27)
				)
			)
		)
		(property "Value" ""
			(at 0 0 90)
			(layer "F.Fab")
			(effects
				(font
					(size 1.27 1.27)
				)
			)
		)
		(duplicate_pad_numbers_are_jumpers no)
		(fp_line
			(start 0.7874 -0.4064)
			(end 0.7874 0.4064)
			(stroke
				(width 0.1524)
				(type default)
			)
			(layer "F.SilkS")
		)
		(fp_line
			(start -0.7874 -0.4064)
			(end 0.7874 -0.4064)
			(stroke
				(width 0.1524)
				(type default)
			)
			(layer "F.SilkS")
		)
		(fp_line
			(start 0.7874 0.4064)
			(end -0.7874 0.4064)
			(stroke
				(width 0.1524)
				(type default)
			)
			(layer "F.SilkS")
		)
		(fp_line
			(start -0.7874 0.4064)
			(end -0.7874 -0.4064)
			(stroke
				(width 0.1524)
				(type default)
			)
			(layer "F.SilkS")
		)
		(fp_line
			(start -0.12065 -0.305054)
			(end -0.12065 -0.2794)
			(stroke
				(width 0.1)
				(type default)
			)
			(layer "F.Fab")
		)
		(fp_line
			(start -0.67945 -0.305054)
			(end -0.12065 -0.305054)
			(stroke
				(width 0.1)
				(type default)
			)
			(layer "F.Fab")
		)
		(fp_line
			(start 0.67945 -0.3048)
			(end 0.67945 0.3048)
			(stroke
				(width 0.1)
				(type default)
			)
			(layer "F.Fab")
		)
		(fp_line
			(start 0.12065 -0.3048)
			(end 0.67945 -0.3048)
			(stroke
				(width 0.1)
				(type default)
			)
			(layer "F.Fab")
		)
		(fp_line
			(start 0.12065 -0.2794)
			(end 0.12065 -0.3048)
			(stroke
				(width 0.1)
				(type default)
			)
			(layer "F.Fab")
		)
		(fp_line
			(start -0.12065 -0.2794)
			(end 0.12065 -0.2794)
			(stroke
				(width 0.1)
				(type default)
			)
			(layer "F.Fab")
		)
		(fp_line
			(start 0.120396 0.2794)
			(end -0.12065 0.2794)
			(stroke
				(width 0.1)
				(type default)
			)
			(layer "F.Fab")
		)
		(fp_line
			(start -0.12065 0.2794)
			(end -0.12065 0.3048)
			(stroke
				(width 0.1)
				(type default)
			)
			(layer "F.Fab")
		)
		(fp_line
			(start 0.67945 0.3048)
			(end 0.120396 0.3048)
			(stroke
				(width 0.1)
				(type default)
			)
			(layer "F.Fab")
		)
		(fp_line
			(start 0.120396 0.3048)
			(end 0.120396 0.2794)
			(stroke
				(width 0.1)
				(type default)
			)
			(layer "F.Fab")
		)
		(fp_line
			(start -0.12065 0.3048)
			(end -0.67945 0.3048)
			(stroke
				(width 0.1)
				(type default)
			)
			(layer "F.Fab")
		)
		(fp_line
			(start -0.67945 0.3048)
			(end -0.67945 -0.305054)
			(stroke
				(width 0.1)
				(type default)
			)
			(layer "F.Fab")
		)
		(pad "1" smd circle
			(at -0.40005 0 90)
			(size 0 0)
			(layers "F.Cu" "F.Mask" "F.Paste")
			(net "FM_CPU0_SMERR_N")
		)
		(pad "2" smd circle
			(at 0.40005 0 90)
			(size 0 0)
			(layers "F.Cu" "F.Mask" "F.Paste")
			(net "CPU0_SMERR_N")
		)
	)
	(footprint ""
		(layer "F.Cu")
		(at 439.029602 -427.09211 180)
		(property "Reference" "C101"
			(at 0 0 180)
			(layer "F.SilkS")
			(hide yes)
			(effects
				(font
					(size 1.27 1.27)
				)
			)
		)
		(property "Value" ""
			(at 0 0 180)
			(layer "F.Fab")
			(effects
				(font
					(size 1.27 1.27)
				)
			)
		)
		(duplicate_pad_numbers_are_jumpers no)
		(fp_line
			(start 0.7874 0.4064)
			(end -0.7874 0.4064)
			(stroke
				(width 0.1524)
				(type default)
			)
			(layer "F.SilkS")
		)
		(fp_line
			(start 0.7874 -0.4064)
			(end 0.7874 0.4064)
			(stroke
				(width 0.1524)
				(type default)
			)
			(layer "F.SilkS")
		)
		(fp_line
			(start -0.7874 0.4064)
			(end -0.7874 -0.4064)
			(stroke
				(width 0.1524)
				(type default)
			)
			(layer "F.SilkS")
		)
		(fp_line
			(start -0.7874 -0.4064)
			(end 0.7874 -0.4064)
			(stroke
				(width 0.1524)
				(type default)
			)
			(layer "F.SilkS")
		)
		(fp_line
			(start 0.67945 0.3048)
			(end 0.120396 0.3048)
			(stroke
				(width 0.1)
				(type default)
			)
			(layer "F.Fab")
		)
		(fp_line
			(start 0.67945 -0.3048)
			(end 0.67945 0.3048)
			(stroke
				(width 0.1)
				(type default)
			)
			(layer "F.Fab")
		)
		(fp_line
			(start 0.12065 -0.2794)
			(end 0.12065 -0.3048)
			(stroke
				(width 0.1)
				(type default)
			)
			(layer "F.Fab")
		)
		(fp_line
			(start 0.12065 -0.3048)
			(end 0.67945 -0.3048)
			(stroke
				(width 0.1)
				(type default)
			)
			(layer "F.Fab")
		)
		(fp_line
			(start 0.120396 0.3048)
			(end 0.120396 0.2794)
			(stroke
				(width 0.1)
				(type default)
			)
			(layer "F.Fab")
		)
		(fp_line
			(start 0.120396 0.2794)
			(end -0.12065 0.2794)
			(stroke
				(width 0.1)
				(type default)
			)
			(layer "F.Fab")
		)
		(fp_line
			(start -0.12065 0.3048)
			(end -0.67945 0.3048)
			(stroke
				(width 0.1)
				(type default)
			)
			(layer "F.Fab")
		)
		(fp_line
			(start -0.12065 0.2794)
			(end -0.12065 0.3048)
			(stroke
				(width 0.1)
				(type default)
			)
			(layer "F.Fab")
		)
		(fp_line
			(start -0.12065 -0.2794)
			(end 0.12065 -0.2794)
			(stroke
				(width 0.1)
				(type default)
			)
			(layer "F.Fab")
		)
		(fp_line
			(start -0.12065 -0.305054)
			(end -0.12065 -0.2794)
			(stroke
				(width 0.1)
				(type default)
			)
			(layer "F.Fab")
		)
		(fp_line
			(start -0.67945 0.3048)
			(end -0.67945 -0.305054)
			(stroke
				(width 0.1)
				(type default)
			)
			(layer "F.Fab")
		)
		(fp_line
			(start -0.67945 -0.305054)
			(end -0.12065 -0.305054)
			(stroke
				(width 0.1)
				(type default)
			)
			(layer "F.Fab")
		)
		(pad "1" smd circle
			(at -0.40005 0 180)
			(size 0 0)
			(layers "F.Cu" "F.Mask" "F.Paste")
			(net "PWRGD_P0V9_RETIMER_CPU0_R")
		)
		(pad "2" smd circle
			(at 0.40005 0 180)
			(size 0 0)
			(layers "F.Cu" "F.Mask" "F.Paste")
			(net "GND")
		)
	)
	(footprint ""
		(layer "F.Cu")
		(at 16.796258 -427.580298 -90)
		(property "Reference" "R6169"
			(at 0 0 270)
			(layer "F.SilkS")
			(hide yes)
			(effects
				(font
					(size 1.27 1.27)
				)
			)
		)
		(property "Value" ""
			(at 0 0 270)
			(layer "F.Fab")
			(effects
				(font
					(size 1.27 1.27)
				)
			)
		)
		(duplicate_pad_numbers_are_jumpers no)
		(fp_line
			(start -0.7874 0.4064)
			(end -0.7874 -0.4064)
			(stroke
				(width 0.1524)
				(type default)
			)
			(layer "F.SilkS")
		)
		(fp_line
			(start 0.7874 0.4064)
			(end -0.7874 0.4064)
			(stroke
				(width 0.1524)
				(type default)
			)
			(layer "F.SilkS")
		)
		(fp_line
			(start -0.7874 -0.4064)
			(end 0.7874 -0.4064)
			(stroke
				(width 0.1524)
				(type default)
			)
			(layer "F.SilkS")
		)
		(fp_line
			(start 0.7874 -0.4064)
			(end 0.7874 0.4064)
			(stroke
				(width 0.1524)
				(type default)
			)
			(layer "F.SilkS")
		)
		(fp_line
			(start -0.67945 0.3048)
			(end -0.67945 -0.305054)
			(stroke
				(width 0.1)
				(type default)
			)
			(layer "F.Fab")
		)
		(fp_line
			(start -0.12065 0.3048)
			(end -0.67945 0.3048)
			(stroke
				(width 0.1)
				(type default)
			)
			(layer "F.Fab")
		)
		(fp_line
			(start 0.120396 0.3048)
			(end 0.120396 0.2794)
			(stroke
				(width 0.1)
				(type default)
			)
			(layer "F.Fab")
		)
		(fp_line
			(start 0.67945 0.3048)
			(end 0.120396 0.3048)
			(stroke
				(width 0.1)
				(type default)
			)
			(layer "F.Fab")
		)
		(fp_line
			(start -0.12065 0.2794)
			(end -0.12065 0.3048)
			(stroke
				(width 0.1)
				(type default)
			)
			(layer "F.Fab")
		)
		(fp_line
			(start 0.120396 0.2794)
			(end -0.12065 0.2794)
			(stroke
				(width 0.1)
				(type default)
			)
			(layer "F.Fab")
		)
		(fp_line
			(start -0.12065 -0.2794)
			(end 0.12065 -0.2794)
			(stroke
				(width 0.1)
				(type default)
			)
			(layer "F.Fab")
		)
		(fp_line
			(start 0.12065 -0.2794)
			(end 0.12065 -0.3048)
			(stroke
				(width 0.1)
				(type default)
			)
			(layer "F.Fab")
		)
		(fp_line
			(start 0.12065 -0.3048)
			(end 0.67945 -0.3048)
			(stroke
				(width 0.1)
				(type default)
			)
			(layer "F.Fab")
		)
		(fp_line
			(start 0.67945 -0.3048)
			(end 0.67945 0.3048)
			(stroke
				(width 0.1)
				(type default)
			)
			(layer "F.Fab")
		)
		(fp_line
			(start -0.67945 -0.305054)
			(end -0.12065 -0.305054)
			(stroke
				(width 0.1)
				(type default)
			)
			(layer "F.Fab")
		)
		(fp_line
			(start -0.12065 -0.305054)
			(end -0.12065 -0.2794)
			(stroke
				(width 0.1)
				(type default)
			)
			(layer "F.Fab")
		)
		(pad "1" smd circle
			(at -0.40005 0 270)
			(size 0 0)
			(layers "F.Cu" "F.Mask" "F.Paste")
			(net "P3V3_AUX")
		)
		(pad "2" smd circle
			(at 0.40005 0 270)
			(size 0 0)
			(layers "F.Cu" "F.Mask" "F.Paste")
			(net "FM_P2E_BUF2_VODA_DB")
		)
	)
	(footprint ""
		(layer "F.Cu")
		(at 274.56638 -421.883332)
		(property "Reference" "JP4003"
			(at -3.4417 8.750808 90)
			(unlocked yes)
			(layer "F.SilkS")
			(effects
				(font
					(size 0.7874 0.5842)
					(thickness 0.1524)
				)
				(justify left)
			)
		)
		(property "Value" ""
			(at 0 0 0)
			(layer "F.Fab")
			(effects
				(font
					(size 1.27 1.27)
				)
			)
		)
		(duplicate_pad_numbers_are_jumpers no)
		(fp_line
			(start -1.249934 -1.320038)
			(end 1.249934 -1.320038)
			(stroke
				(width 0.1524)
				(type default)
			)
			(layer "F.SilkS")
		)
		(fp_line
			(start -1.249934 6.400038)
			(end -1.249934 -1.320038)
			(stroke
				(width 0.1524)
				(type default)
			)
			(layer "F.SilkS")
		)
		(fp_line
			(start 1.249934 -1.320038)
			(end 1.249934 6.400038)
			(stroke
				(width 0.1524)
				(type default)
			)
			(layer "F.SilkS")
		)
		(fp_line
			(start 1.249934 6.400038)
			(end -1.249934 6.400038)
			(stroke
				(width 0.1524)
				(type default)
			)
			(layer "F.SilkS")
		)
		(fp_poly
			(pts
				(xy -2.5654 0.556514) (xy -2.5654 -0.556514) (xy -1.452372 0)
			)
			(stroke
				(width 0)
				(type default)
			)
			(fill yes)
			(layer "F.SilkS")
		)
		(fp_line
			(start -1.249934 -1.320038)
			(end 1.249934 -1.320038)
			(stroke
				(width 0.1)
				(type default)
			)
			(layer "F.Fab")
		)
		(fp_line
			(start -1.249934 6.400038)
			(end -1.249934 -1.320038)
			(stroke
				(width 0.1)
				(type default)
			)
			(layer "F.Fab")
		)
		(fp_line
			(start 1.249934 -1.320038)
			(end 1.249934 6.400038)
			(stroke
				(width 0.1)
				(type default)
			)
			(layer "F.Fab")
		)
		(fp_line
			(start 1.249934 6.400038)
			(end -1.249934 6.400038)
			(stroke
				(width 0.1)
				(type default)
			)
			(layer "F.Fab")
		)
		(fp_poly
			(pts
				(xy -2.5654 -0.556514) (xy -1.452372 0) (xy -2.5654 0.556514)
			)
			(stroke
				(width 0)
				(type default)
			)
			(fill yes)
			(layer "F.Fab")
		)
		(fp_text user "3"
			(at -2.007362 5.130292 90)
			(unlocked yes)
			(layer "F.SilkS")
			(effects
				(font
					(size 0.7874 0.5842)
					(thickness 0.1524)
				)
			)
		)
		(fp_text user "3"
			(at -1.1557 5.18287 0)
			(unlocked yes)
			(layer "B.SilkS")
			(effects
				(font
					(size 0.7874 0.5842)
					(thickness 0.1524)
				)
				(justify mirror)
			)
		)
		(fp_text user "1"
			(at -1.143 0.02667 0)
			(unlocked yes)
			(layer "B.SilkS")
			(effects
				(font
					(size 0.7874 0.5842)
					(thickness 0.1524)
				)
				(justify mirror)
			)
		)
		(fp_text user "3"
			(at -1.1557 5.18287 0)
			(unlocked yes)
			(layer "B.Fab")
			(effects
				(font
					(size 0.7874 0.5842)
					(thickness 0.1524)
				)
				(justify mirror)
			)
		)
		(fp_text user "1"
			(at -1.143 0.02667 0)
			(unlocked yes)
			(layer "B.Fab")
			(effects
				(font
					(size 0.7874 0.5842)
					(thickness 0.1524)
				)
				(justify mirror)
			)
		)
		(fp_text user "3"
			(at -1.778 5.13207 0)
			(unlocked yes)
			(layer "F.Fab")
			(effects
				(font
					(size 0.7874 0.5842)
					(thickness 0.1524)
				)
			)
		)
		(pad "1" thru_hole rect
			(at 0 0)
			(size 1.5494 1.5494)
			(drill 1.0414)
			(layers "*.Cu" "*.Mask")
			(remove_unused_layers no)
			(net "Net_10750")
			(clearance 0)
			(padstack
				(mode front_inner_back)
				(layer "Inner"
					(shape circle)
					(size 1.5494 1.5494)
					(clearance 0)
				)
				(layer "B.Cu"
					(shape rect)
					(size 1.5494 1.5494)
					(clearance 0)
				)
			)
		)
		(pad "2" thru_hole circle
			(at 0 2.54)
			(size 1.5494 1.5494)
			(drill 1.0414)
			(layers "*.Cu" "*.Mask")
			(remove_unused_layers no)
			(net "PDB_PRSNT_R_N")
			(clearance 0)
		)
		(pad "3" thru_hole circle
			(at 0 5.08)
			(size 1.5494 1.5494)
			(drill 1.0414)
			(layers "*.Cu" "*.Mask")
			(remove_unused_layers no)
			(net "GND")
			(clearance 0)
		)
	)
	(footprint ""
		(layer "F.Cu")
		(at 257.242056 -119.92737 180)
		(property "Reference" "R3716"
			(at 0 0 180)
			(layer "F.SilkS")
			(hide yes)
			(effects
				(font
					(size 1.27 1.27)
				)
			)
		)
		(property "Value" ""
			(at 0 0 180)
			(layer "F.Fab")
			(effects
				(font
					(size 1.27 1.27)
				)
			)
		)
		(duplicate_pad_numbers_are_jumpers no)
		(fp_line
			(start 0.7874 0.4064)
			(end -0.7874 0.4064)
			(stroke
				(width 0.1524)
				(type default)
			)
			(layer "F.SilkS")
		)
		(fp_line
			(start 0.7874 -0.4064)
			(end 0.7874 0.4064)
			(stroke
				(width 0.1524)
				(type default)
			)
			(layer "F.SilkS")
		)
		(fp_line
			(start -0.7874 0.4064)
			(end -0.7874 -0.4064)
			(stroke
				(width 0.1524)
				(type default)
			)
			(layer "F.SilkS")
		)
		(fp_line
			(start -0.7874 -0.4064)
			(end 0.7874 -0.4064)
			(stroke
				(width 0.1524)
				(type default)
			)
			(layer "F.SilkS")
		)
		(fp_line
			(start 0.67945 0.3048)
			(end 0.120396 0.3048)
			(stroke
				(width 0.1)
				(type default)
			)
			(layer "F.Fab")
		)
		(fp_line
			(start 0.67945 -0.3048)
			(end 0.67945 0.3048)
			(stroke
				(width 0.1)
				(type default)
			)
			(layer "F.Fab")
		)
		(fp_line
			(start 0.12065 -0.2794)
			(end 0.12065 -0.3048)
			(stroke
				(width 0.1)
				(type default)
			)
			(layer "F.Fab")
		)
		(fp_line
			(start 0.12065 -0.3048)
			(end 0.67945 -0.3048)
			(stroke
				(width 0.1)
				(type default)
			)
			(layer "F.Fab")
		)
		(fp_line
			(start 0.120396 0.3048)
			(end 0.120396 0.2794)
			(stroke
				(width 0.1)
				(type default)
			)
			(layer "F.Fab")
		)
		(fp_line
			(start 0.120396 0.2794)
			(end -0.12065 0.2794)
			(stroke
				(width 0.1)
				(type default)
			)
			(layer "F.Fab")
		)
		(fp_line
			(start -0.12065 0.3048)
			(end -0.67945 0.3048)
			(stroke
				(width 0.1)
				(type default)
			)
			(layer "F.Fab")
		)
		(fp_line
			(start -0.12065 0.2794)
			(end -0.12065 0.3048)
			(stroke
				(width 0.1)
				(type default)
			)
			(layer "F.Fab")
		)
		(fp_line
			(start -0.12065 -0.2794)
			(end 0.12065 -0.2794)
			(stroke
				(width 0.1)
				(type default)
			)
			(layer "F.Fab")
		)
		(fp_line
			(start -0.12065 -0.305054)
			(end -0.12065 -0.2794)
			(stroke
				(width 0.1)
				(type default)
			)
			(layer "F.Fab")
		)
		(fp_line
			(start -0.67945 0.3048)
			(end -0.67945 -0.305054)
			(stroke
				(width 0.1)
				(type default)
			)
			(layer "F.Fab")
		)
		(fp_line
			(start -0.67945 -0.305054)
			(end -0.12065 -0.305054)
			(stroke
				(width 0.1)
				(type default)
			)
			(layer "F.Fab")
		)
		(pad "1" smd circle
			(at -0.40005 0 180)
			(size 0 0)
			(layers "F.Cu" "F.Mask" "F.Paste")
			(net "SMB_LM75_0_3V3AUX_SDA_R")
		)
		(pad "2" smd circle
			(at 0.40005 0 180)
			(size 0 0)
			(layers "F.Cu" "F.Mask" "F.Paste")
			(net "SMB_LM75_0_3V3AUX_SDA")
		)
	)
)
